(kicad_pcb
	(version 20260206)
	(generator "pcbnew")
	(generator_version "10.0")
	(general
		(thickness 1.6)
		(legacy_teardrops no)
	)
	(paper "A4")
	(title_block
		(title "panther-plus-userver — 13130-1b_20150205.brd")
		(comment 1 "Honey Badger (Wiwynn) / footprint 894 of 1509 (DIMM1), pads 107-113 of 210")
	)
	(layers
		(0 "F.Cu" signal "TOP")
		(4 "In1.Cu" signal "L2")
		(6 "In2.Cu" signal "L3")
		(8 "In3.Cu" signal "L4")
		(10 "In4.Cu" signal "L5")
		(12 "In5.Cu" signal "L6")
		(14 "In6.Cu" signal "L7")
		(16 "In7.Cu" signal "L8")
		(18 "In8.Cu" signal "L9")
		(20 "In9.Cu" signal "L10")
		(22 "In10.Cu" signal "L11")
		(2 "B.Cu" signal "BOTTOM")
		(9 "F.Adhes" user "F.Adhesive")
		(11 "B.Adhes" user "B.Adhesive")
		(13 "F.Paste" user "Package Geometry/Pastemask Top")
		(15 "B.Paste" user "Package Geometry/Pastemask Bottom")
		(5 "F.SilkS" user "Ref Des/Silkscreen Top")
		(7 "B.SilkS" user "Ref Des/Silkscreen Bottom")
		(1 "F.Mask" user "Board Geometry/Soldermask Top")
		(3 "B.Mask" user "Board Geometry/Soldermask Bottom")
		(17 "Dwgs.User" user "User.Drawings")
		(19 "Cmts.User" user "User.Comments")
		(21 "Eco1.User" user "User.Eco1")
		(23 "Eco2.User" user "User.Eco2")
		(25 "Edge.Cuts" user "Board Geometry/Outline")
		(27 "Margin" user)
		(31 "F.CrtYd" user "Package Geometry/Place Bound Top")
		(29 "B.CrtYd" user "Package Geometry/Place Bound Bottom")
		(35 "F.Fab" user "Ref Des/Assembly Top")
		(33 "B.Fab" user "Ref Des/Assembly Bottom")
	)
	(footprint ""
		(layer "B.Cu")
		(at 158.500064 -66.699892 180)
		(property "Reference" "DIMM1"
			(at 0 0 0)
			(layer "B.SilkS")
			(hide yes)
			(effects
				(font
					(size 1.27 1.27)
				)
				(justify mirror)
			)
		)
		(property "Value" "DDR3-204P-142-COLAY-1-GP-U"
			(at 41.312338 -16.676878 180)
			(unlocked yes)
			(layer "B.Fab")
			(hide yes)
			(effects
				(font
					(size 1.016 1.016)
					(thickness 0.1524)
				)
				(justify mirror)
			)
		)
		(property "Device Type" "AS0A626-J8R6-7H-COLAY-1"
			(at 41.312338 -18.200878 180)
			(unlocked yes)
			(layer "B.Fab")
			(hide yes)
			(effects
				(font
					(size 1.016 1.016)
					(thickness 0.1524)
				)
				(justify mirror)
			)
		)
		(duplicate_pad_numbers_are_jumpers no)
		(pad "105" smd custom
			(at 1.949958 -4.100068)
			(size 0.1143 0.1143)
			(layers "B.Cu" "B.Mask" "B.Paste")
			(net "M_A_MA1")
			(options
				(clearance outline)
				(anchor circle)
			)
			(primitives
				(gr_poly
					(pts
						(xy 0 -0.9017) (xy -0.03175 -0.89916) (xy -0.0635 -0.889) (xy -0.09144 -0.87376) (xy -0.11684 -0.85344)
						(xy -0.13716 -0.82804) (xy -0.1524 -0.8001) (xy -0.16256 -0.76835) (xy -0.1651 -0.7366) (xy -0.1651 -0.44958)
						(xy -0.17272 -0.44196) (xy -0.19812 -0.4064) (xy -0.2032 -0.39624) (xy -0.20701 -0.38735) (xy -0.21209 -0.37719)
						(xy -0.2159 -0.36703) (xy -0.21844 -0.35687) (xy -0.22225 -0.34544) (xy -0.22352 -0.33528) (xy -0.22606 -0.32512)
						(xy -0.22733 -0.31369) (xy -0.22733 -0.30353) (xy -0.2286 -0.2921) (xy -0.22733 -0.28067) (xy -0.22733 -0.27051)
						(xy -0.22606 -0.25908) (xy -0.22352 -0.24892) (xy -0.22225 -0.23876) (xy -0.21844 -0.22733) (xy -0.2159 -0.21717)
						(xy -0.21209 -0.20701) (xy -0.20701 -0.19685) (xy -0.2032 -0.18796) (xy -0.19812 -0.1778) (xy -0.17272 -0.14224)
						(xy -0.1651 -0.13462) (xy -0.1651 0.7366) (xy -0.16256 0.76835) (xy -0.1524 0.8001) (xy -0.13716 0.82804)
						(xy -0.11684 0.85344) (xy -0.09144 0.87376) (xy -0.0635 0.889) (xy -0.03175 0.89916) (xy 0 0.9017)
						(xy 0.03175 0.89916) (xy 0.0635 0.889) (xy 0.09144 0.87376) (xy 0.11684 0.85344) (xy 0.13716 0.82804)
						(xy 0.1524 0.8001) (xy 0.16256 0.76835) (xy 0.1651 0.7366) (xy 0.1651 -0.13462) (xy 0.17272 -0.14224)
						(xy 0.19812 -0.1778) (xy 0.2032 -0.18796) (xy 0.20701 -0.19685) (xy 0.21209 -0.20701) (xy 0.2159 -0.21717)
						(xy 0.21844 -0.22733) (xy 0.22225 -0.23876) (xy 0.22352 -0.24892) (xy 0.22606 -0.25908) (xy 0.22733 -0.27051)
						(xy 0.22733 -0.28067) (xy 0.2286 -0.2921) (xy 0.22733 -0.30353) (xy 0.22733 -0.31369) (xy 0.22606 -0.32512)
						(xy 0.22352 -0.33528) (xy 0.22225 -0.34544) (xy 0.21844 -0.35687) (xy 0.2159 -0.36703) (xy 0.21209 -0.37719)
						(xy 0.20701 -0.38735) (xy 0.2032 -0.39624) (xy 0.19812 -0.4064) (xy 0.17272 -0.44196) (xy 0.1651 -0.44958)
						(xy 0.1651 -0.7366) (xy 0.16256 -0.76835) (xy 0.1524 -0.8001) (xy 0.13716 -0.82804) (xy 0.11684 -0.85344)
						(xy 0.09144 -0.87376) (xy 0.0635 -0.889) (xy 0.03175 -0.89916)
					)
					(width 0)
					(fill yes)
				)
			)
		)
		(pad "106" smd custom
			(at 2.249932 4.100068)
			(size 0.1143 0.1143)
			(layers "B.Cu" "B.Mask" "B.Paste")
			(net "M_A_MA2")
			(options
				(clearance outline)
				(anchor circle)
			)
			(primitives
				(gr_poly
					(pts
						(xy 0 -0.9017) (xy -0.03175 -0.89916) (xy -0.0635 -0.889) (xy -0.09144 -0.87376) (xy -0.11684 -0.85344)
						(xy -0.13716 -0.82804) (xy -0.1524 -0.8001) (xy -0.16256 -0.76835) (xy -0.1651 -0.7366) (xy -0.1651 0.13462)
						(xy -0.17272 0.14224) (xy -0.19812 0.1778) (xy -0.2032 0.18796) (xy -0.20701 0.19685) (xy -0.21209 0.20701)
						(xy -0.2159 0.21717) (xy -0.21844 0.22733) (xy -0.22225 0.23876) (xy -0.22352 0.24892) (xy -0.22606 0.25908)
						(xy -0.22733 0.27051) (xy -0.22733 0.28067) (xy -0.2286 0.2921) (xy -0.22733 0.30353) (xy -0.22733 0.31369)
						(xy -0.22606 0.32512) (xy -0.22352 0.33528) (xy -0.22225 0.34544) (xy -0.21844 0.35687) (xy -0.2159 0.36703)
						(xy -0.21209 0.37719) (xy -0.20701 0.38735) (xy -0.2032 0.39624) (xy -0.19812 0.4064) (xy -0.17272 0.44196)
						(xy -0.1651 0.44958) (xy -0.1651 0.7366) (xy -0.16256 0.76835) (xy -0.1524 0.8001) (xy -0.13716 0.82804)
						(xy -0.11684 0.85344) (xy -0.09144 0.87376) (xy -0.0635 0.889) (xy -0.03175 0.89916) (xy 0 0.9017)
						(xy 0.03175 0.89916) (xy 0.0635 0.889) (xy 0.09144 0.87376) (xy 0.11684 0.85344) (xy 0.13716 0.82804)
						(xy 0.1524 0.8001) (xy 0.16256 0.76835) (xy 0.1651 0.7366) (xy 0.1651 0.44958) (xy 0.17272 0.44196)
						(xy 0.19812 0.4064) (xy 0.2032 0.39624) (xy 0.20701 0.38735) (xy 0.21209 0.37719) (xy 0.2159 0.36703)
						(xy 0.21844 0.35687) (xy 0.22225 0.34544) (xy 0.22352 0.33528) (xy 0.22606 0.32512) (xy 0.22733 0.31369)
						(xy 0.22733 0.30353) (xy 0.2286 0.2921) (xy 0.22733 0.28067) (xy 0.22733 0.27051) (xy 0.22606 0.25908)
						(xy 0.22352 0.24892) (xy 0.22225 0.23876) (xy 0.21844 0.22733) (xy 0.2159 0.21717) (xy 0.21209 0.20701)
						(xy 0.20701 0.19685) (xy 0.2032 0.18796) (xy 0.19812 0.1778) (xy 0.17272 0.14224) (xy 0.1651 0.13462)
						(xy 0.1651 -0.7366) (xy 0.16256 -0.76835) (xy 0.1524 -0.8001) (xy 0.13716 -0.82804) (xy 0.11684 -0.85344)
						(xy 0.09144 -0.87376) (xy 0.0635 -0.889) (xy 0.03175 -0.89916)
					)
					(width 0)
					(fill yes)
				)
			)
		)
		(pad "107" smd custom
			(at 2.549906 -4.100068)
			(size 0.1143 0.1143)
			(layers "B.Cu" "B.Mask" "B.Paste")
			(net "M_A_MA0")
			(options
				(clearance outline)
				(anchor circle)
			)
			(primitives
				(gr_poly
					(pts
						(xy 0 -0.9017) (xy -0.03175 -0.89916) (xy -0.0635 -0.889) (xy -0.09144 -0.87376) (xy -0.11684 -0.85344)
						(xy -0.13716 -0.82804) (xy -0.1524 -0.8001) (xy -0.16256 -0.76835) (xy -0.1651 -0.7366) (xy -0.1651 -0.19685)
						(xy -0.17272 -0.18923) (xy -0.17907 -0.18034) (xy -0.18669 -0.17145) (xy -0.19177 -0.16256) (xy -0.19812 -0.15367)
						(xy -0.20828 -0.13335) (xy -0.21971 -0.10287) (xy -0.22225 -0.09271) (xy -0.22479 -0.08128) (xy -0.22606 -0.07112)
						(xy -0.2286 -0.05969) (xy -0.2286 -0.01651) (xy -0.22606 -0.00508) (xy -0.22479 0.00508) (xy -0.22225 0.01651)
						(xy -0.21971 0.02667) (xy -0.20828 0.05715) (xy -0.19812 0.07747) (xy -0.19177 0.08636) (xy -0.18669 0.09525)
						(xy -0.17907 0.10414) (xy -0.17272 0.11303) (xy -0.1651 0.12065) (xy -0.1651 0.7366) (xy -0.16256 0.76835)
						(xy -0.1524 0.8001) (xy -0.13716 0.82804) (xy -0.11684 0.85344) (xy -0.09144 0.87376) (xy -0.0635 0.889)
						(xy -0.03175 0.89916) (xy 0 0.9017) (xy 0.03175 0.89916) (xy 0.0635 0.889) (xy 0.09144 0.87376)
						(xy 0.11684 0.85344) (xy 0.13716 0.82804) (xy 0.1524 0.8001) (xy 0.16256 0.76835) (xy 0.1651 0.7366)
						(xy 0.1651 0.11938) (xy 0.17272 0.11176) (xy 0.19812 0.0762) (xy 0.2032 0.06604) (xy 0.20701 0.05715)
						(xy 0.21209 0.04699) (xy 0.2159 0.03683) (xy 0.21844 0.02667) (xy 0.22225 0.01524) (xy 0.22352 0.00508)
						(xy 0.22606 -0.00508) (xy 0.22733 -0.01651) (xy 0.22733 -0.02667) (xy 0.2286 -0.0381) (xy 0.22733 -0.04953)
						(xy 0.22733 -0.05969) (xy 0.22606 -0.07112) (xy 0.22352 -0.08128) (xy 0.22225 -0.09144) (xy 0.21844 -0.10287)
						(xy 0.2159 -0.11303) (xy 0.21209 -0.12319) (xy 0.20701 -0.13335) (xy 0.2032 -0.14224) (xy 0.19812 -0.1524)
						(xy 0.17272 -0.18796) (xy 0.1651 -0.19558) (xy 0.1651 -0.7366) (xy 0.16256 -0.76835) (xy 0.1524 -0.8001)
						(xy 0.13716 -0.82804) (xy 0.11684 -0.85344) (xy 0.09144 -0.87376) (xy 0.0635 -0.889) (xy 0.03175 -0.89916)
					)
					(width 0)
					(fill yes)
				)
			)
		)
		(pad "108" smd custom
			(at 2.84988 4.100068)
			(size 0.1143 0.1143)
			(layers "B.Cu" "B.Mask" "B.Paste")
			(net "M_A_BS1")
			(options
				(clearance outline)
				(anchor circle)
			)
			(primitives
				(gr_poly
					(pts
						(xy 0 -0.9017) (xy -0.03175 -0.89916) (xy -0.0635 -0.889) (xy -0.09144 -0.87376) (xy -0.11684 -0.85344)
						(xy -0.13716 -0.82804) (xy -0.1524 -0.8001) (xy -0.16256 -0.76835) (xy -0.1651 -0.7366) (xy -0.1651 -0.11938)
						(xy -0.17272 -0.11176) (xy -0.19812 -0.0762) (xy -0.2032 -0.06604) (xy -0.20701 -0.05715) (xy -0.21209 -0.04699)
						(xy -0.2159 -0.03683) (xy -0.21844 -0.02667) (xy -0.22225 -0.01524) (xy -0.22352 -0.00508) (xy -0.22606 0.00508)
						(xy -0.22733 0.01651) (xy -0.22733 0.02667) (xy -0.2286 0.0381) (xy -0.22733 0.04953) (xy -0.22733 0.05969)
						(xy -0.22606 0.07112) (xy -0.22352 0.08128) (xy -0.22225 0.09144) (xy -0.21844 0.10287) (xy -0.2159 0.11303)
						(xy -0.21209 0.12319) (xy -0.20701 0.13335) (xy -0.2032 0.14224) (xy -0.19812 0.1524) (xy -0.17272 0.18796)
						(xy -0.1651 0.19558) (xy -0.1651 0.7366) (xy -0.16256 0.76835) (xy -0.1524 0.8001) (xy -0.13716 0.82804)
						(xy -0.11684 0.85344) (xy -0.09144 0.87376) (xy -0.0635 0.889) (xy -0.03175 0.89916) (xy 0 0.9017)
						(xy 0.03175 0.89916) (xy 0.0635 0.889) (xy 0.09144 0.87376) (xy 0.11684 0.85344) (xy 0.13716 0.82804)
						(xy 0.1524 0.8001) (xy 0.16256 0.76835) (xy 0.1651 0.7366) (xy 0.1651 0.19685) (xy 0.17272 0.18923)
						(xy 0.17907 0.18034) (xy 0.18669 0.17145) (xy 0.19177 0.16256) (xy 0.19812 0.15367) (xy 0.20828 0.13335)
						(xy 0.21971 0.10287) (xy 0.22225 0.09271) (xy 0.22479 0.08128) (xy 0.22606 0.07112) (xy 0.2286 0.05969)
						(xy 0.2286 0.01651) (xy 0.22606 0.00508) (xy 0.22479 -0.00508) (xy 0.22225 -0.01651) (xy 0.21971 -0.02667)
						(xy 0.20828 -0.05715) (xy 0.19812 -0.07747) (xy 0.19177 -0.08636) (xy 0.18669 -0.09525) (xy 0.17907 -0.10414)
						(xy 0.17272 -0.11303) (xy 0.1651 -0.12065) (xy 0.1651 -0.7366) (xy 0.16256 -0.76835) (xy 0.1524 -0.8001)
						(xy 0.13716 -0.82804) (xy 0.11684 -0.85344) (xy 0.09144 -0.87376) (xy 0.0635 -0.889) (xy 0.03175 -0.89916)
					)
					(width 0)
					(fill yes)
				)
			)
		)
		(pad "109" smd custom
			(at 3.150108 -4.100068)
			(size 0.1143 0.1143)
			(layers "B.Cu" "B.Mask" "B.Paste")
			(net "PV_VDDR")
			(options
				(clearance outline)
				(anchor circle)
			)
			(primitives
				(gr_poly
					(pts
						(xy 0 -0.9017) (xy -0.03175 -0.89916) (xy -0.0635 -0.889) (xy -0.09144 -0.87376) (xy -0.11684 -0.85344)
						(xy -0.13716 -0.82804) (xy -0.1524 -0.8001) (xy -0.16256 -0.76835) (xy -0.1651 -0.7366) (xy -0.1651 -0.44958)
						(xy -0.17272 -0.44196) (xy -0.19812 -0.4064) (xy -0.2032 -0.39624) (xy -0.20701 -0.38735) (xy -0.21209 -0.37719)
						(xy -0.2159 -0.36703) (xy -0.21844 -0.35687) (xy -0.22225 -0.34544) (xy -0.22352 -0.33528) (xy -0.22606 -0.32512)
						(xy -0.22733 -0.31369) (xy -0.22733 -0.30353) (xy -0.2286 -0.2921) (xy -0.22733 -0.28067) (xy -0.22733 -0.27051)
						(xy -0.22606 -0.25908) (xy -0.22352 -0.24892) (xy -0.22225 -0.23876) (xy -0.21844 -0.22733) (xy -0.2159 -0.21717)
						(xy -0.21209 -0.20701) (xy -0.20701 -0.19685) (xy -0.2032 -0.18796) (xy -0.19812 -0.1778) (xy -0.17272 -0.14224)
						(xy -0.1651 -0.13462) (xy -0.1651 0.7366) (xy -0.16256 0.76835) (xy -0.1524 0.8001) (xy -0.13716 0.82804)
						(xy -0.11684 0.85344) (xy -0.09144 0.87376) (xy -0.0635 0.889) (xy -0.03175 0.89916) (xy 0 0.9017)
						(xy 0.03175 0.89916) (xy 0.0635 0.889) (xy 0.09144 0.87376) (xy 0.11684 0.85344) (xy 0.13716 0.82804)
						(xy 0.1524 0.8001) (xy 0.16256 0.76835) (xy 0.1651 0.7366) (xy 0.1651 -0.13462) (xy 0.17272 -0.14224)
						(xy 0.19812 -0.1778) (xy 0.2032 -0.18796) (xy 0.20701 -0.19685) (xy 0.21209 -0.20701) (xy 0.2159 -0.21717)
						(xy 0.21844 -0.22733) (xy 0.22225 -0.23876) (xy 0.22352 -0.24892) (xy 0.22606 -0.25908) (xy 0.22733 -0.27051)
						(xy 0.22733 -0.28067) (xy 0.2286 -0.2921) (xy 0.22733 -0.30353) (xy 0.22733 -0.31369) (xy 0.22606 -0.32512)
						(xy 0.22352 -0.33528) (xy 0.22225 -0.34544) (xy 0.21844 -0.35687) (xy 0.2159 -0.36703) (xy 0.21209 -0.37719)
						(xy 0.20701 -0.38735) (xy 0.2032 -0.39624) (xy 0.19812 -0.4064) (xy 0.17272 -0.44196) (xy 0.1651 -0.44958)
						(xy 0.1651 -0.7366) (xy 0.16256 -0.76835) (xy 0.1524 -0.8001) (xy 0.13716 -0.82804) (xy 0.11684 -0.85344)
						(xy 0.09144 -0.87376) (xy 0.0635 -0.889) (xy 0.03175 -0.89916)
					)
					(width 0)
					(fill yes)
				)
			)
		)
		(pad "110" smd custom
			(at 3.450082 4.100068)
			(size 0.1143 0.1143)
			(layers "B.Cu" "B.Mask" "B.Paste")
			(net "PV_VDDR")
			(options
				(clearance outline)
				(anchor circle)
			)
			(primitives
				(gr_poly
					(pts
						(xy 0 -0.9017) (xy -0.03175 -0.89916) (xy -0.0635 -0.889) (xy -0.09144 -0.87376) (xy -0.11684 -0.85344)
						(xy -0.13716 -0.82804) (xy -0.1524 -0.8001) (xy -0.16256 -0.76835) (xy -0.1651 -0.7366) (xy -0.1651 0.13462)
						(xy -0.17272 0.14224) (xy -0.19812 0.1778) (xy -0.2032 0.18796) (xy -0.20701 0.19685) (xy -0.21209 0.20701)
						(xy -0.2159 0.21717) (xy -0.21844 0.22733) (xy -0.22225 0.23876) (xy -0.22352 0.24892) (xy -0.22606 0.25908)
						(xy -0.22733 0.27051) (xy -0.22733 0.28067) (xy -0.2286 0.2921) (xy -0.22733 0.30353) (xy -0.22733 0.31369)
						(xy -0.22606 0.32512) (xy -0.22352 0.33528) (xy -0.22225 0.34544) (xy -0.21844 0.35687) (xy -0.2159 0.36703)
						(xy -0.21209 0.37719) (xy -0.20701 0.38735) (xy -0.2032 0.39624) (xy -0.19812 0.4064) (xy -0.17272 0.44196)
						(xy -0.1651 0.44958) (xy -0.1651 0.7366) (xy -0.16256 0.76835) (xy -0.1524 0.8001) (xy -0.13716 0.82804)
						(xy -0.11684 0.85344) (xy -0.09144 0.87376) (xy -0.0635 0.889) (xy -0.03175 0.89916) (xy 0 0.9017)
						(xy 0.03175 0.89916) (xy 0.0635 0.889) (xy 0.09144 0.87376) (xy 0.11684 0.85344) (xy 0.13716 0.82804)
						(xy 0.1524 0.8001) (xy 0.16256 0.76835) (xy 0.1651 0.7366) (xy 0.1651 0.44958) (xy 0.17272 0.44196)
						(xy 0.19812 0.4064) (xy 0.2032 0.39624) (xy 0.20701 0.38735) (xy 0.21209 0.37719) (xy 0.2159 0.36703)
						(xy 0.21844 0.35687) (xy 0.22225 0.34544) (xy 0.22352 0.33528) (xy 0.22606 0.32512) (xy 0.22733 0.31369)
						(xy 0.22733 0.30353) (xy 0.2286 0.2921) (xy 0.22733 0.28067) (xy 0.22733 0.27051) (xy 0.22606 0.25908)
						(xy 0.22352 0.24892) (xy 0.22225 0.23876) (xy 0.21844 0.22733) (xy 0.2159 0.21717) (xy 0.21209 0.20701)
						(xy 0.20701 0.19685) (xy 0.2032 0.18796) (xy 0.19812 0.1778) (xy 0.17272 0.14224) (xy 0.1651 0.13462)
						(xy 0.1651 -0.7366) (xy 0.16256 -0.76835) (xy 0.1524 -0.8001) (xy 0.13716 -0.82804) (xy 0.11684 -0.85344)
						(xy 0.09144 -0.87376) (xy 0.0635 -0.889) (xy 0.03175 -0.89916)
					)
					(width 0)
					(fill yes)
				)
			)
		)
		(pad "111" smd custom
			(at 3.750056 -4.100068)
			(size 0.1143 0.1143)
			(layers "B.Cu" "B.Mask" "B.Paste")
			(net "M_A_CK_DP0")
			(options
				(clearance outline)
				(anchor circle)
			)
			(primitives
				(gr_poly
					(pts
						(xy 0 -0.9017) (xy -0.03175 -0.89916) (xy -0.0635 -0.889) (xy -0.09144 -0.87376) (xy -0.11684 -0.85344)
						(xy -0.13716 -0.82804) (xy -0.1524 -0.8001) (xy -0.16256 -0.76835) (xy -0.1651 -0.7366) (xy -0.1651 -0.19685)
						(xy -0.17272 -0.18923) (xy -0.17907 -0.18034) (xy -0.18669 -0.17145) (xy -0.19177 -0.16256) (xy -0.19812 -0.15367)
						(xy -0.20828 -0.13335) (xy -0.21971 -0.10287) (xy -0.22225 -0.09271) (xy -0.22479 -0.08128) (xy -0.22606 -0.07112)
						(xy -0.2286 -0.05969) (xy -0.2286 -0.01651) (xy -0.22606 -0.00508) (xy -0.22479 0.00508) (xy -0.22225 0.01651)
						(xy -0.21971 0.02667) (xy -0.20828 0.05715) (xy -0.19812 0.07747) (xy -0.19177 0.08636) (xy -0.18669 0.09525)
						(xy -0.17907 0.10414) (xy -0.17272 0.11303) (xy -0.1651 0.12065) (xy -0.1651 0.7366) (xy -0.16256 0.76835)
						(xy -0.1524 0.8001) (xy -0.13716 0.82804) (xy -0.11684 0.85344) (xy -0.09144 0.87376) (xy -0.0635 0.889)
						(xy -0.03175 0.89916) (xy 0 0.9017) (xy 0.03175 0.89916) (xy 0.0635 0.889) (xy 0.09144 0.87376)
						(xy 0.11684 0.85344) (xy 0.13716 0.82804) (xy 0.1524 0.8001) (xy 0.16256 0.76835) (xy 0.1651 0.7366)
						(xy 0.1651 0.11938) (xy 0.17272 0.11176) (xy 0.19812 0.0762) (xy 0.2032 0.06604) (xy 0.20701 0.05715)
						(xy 0.21209 0.04699) (xy 0.2159 0.03683) (xy 0.21844 0.02667) (xy 0.22225 0.01524) (xy 0.22352 0.00508)
						(xy 0.22606 -0.00508) (xy 0.22733 -0.01651) (xy 0.22733 -0.02667) (xy 0.2286 -0.0381) (xy 0.22733 -0.04953)
						(xy 0.22733 -0.05969) (xy 0.22606 -0.07112) (xy 0.22352 -0.08128) (xy 0.22225 -0.09144) (xy 0.21844 -0.10287)
						(xy 0.2159 -0.11303) (xy 0.21209 -0.12319) (xy 0.20701 -0.13335) (xy 0.2032 -0.14224) (xy 0.19812 -0.1524)
						(xy 0.17272 -0.18796) (xy 0.1651 -0.19558) (xy 0.1651 -0.7366) (xy 0.16256 -0.76835) (xy 0.1524 -0.8001)
						(xy 0.13716 -0.82804) (xy 0.11684 -0.85344) (xy 0.09144 -0.87376) (xy 0.0635 -0.889) (xy 0.03175 -0.89916)
					)
					(width 0)
					(fill yes)
				)
			)
		)
	)
)
